(kicad_pcb
	(version 20241229)
	(generator "pcbnew")
	(generator_version "9.0")
	(general
		(thickness 1.552)
		(legacy_teardrops no)
	)
	(paper "A4")
	(title_block
		(date "2023-07-25")
		(rev "1.1.4")
		(comment 9 "footprints 234-237 of 379")
	)
	(layers
		(0 "F.Cu" signal)
		(4 "In1.Cu" signal)
		(6 "In2.Cu" signal)
		(8 "In3.Cu" signal)
		(10 "In4.Cu" signal)
		(12 "In5.Cu" signal)
		(14 "In6.Cu" signal)
		(2 "B.Cu" signal)
		(9 "F.Adhes" user "F.Adhesive")
		(11 "B.Adhes" user "B.Adhesive")
		(13 "F.Paste" user)
		(15 "B.Paste" user)
		(5 "F.SilkS" user "F.Silkscreen")
		(7 "B.SilkS" user "B.Silkscreen")
		(1 "F.Mask" user)
		(3 "B.Mask" user)
		(17 "Dwgs.User" user "User.Drawings")
		(19 "Cmts.User" user "User.Comments")
		(21 "Eco1.User" user "User.Eco1")
		(23 "Eco2.User" user "User.Eco2")
		(25 "Edge.Cuts" user)
		(27 "Margin" user)
		(31 "F.CrtYd" user "F.Courtyard")
		(29 "B.CrtYd" user "B.Courtyard")
		(35 "F.Fab" user)
		(33 "B.Fab" user)
	)
	(footprint "antmicro-footprints:TP_SMD_0.75mm"
		(layer "F.Cu")
		(at 150.82 69.6008)
		(property "Reference" "TP9"
			(at 0.31 -0.3608 0)
			(layer "F.SilkS")
			(effects
				(font
					(size 0.65 0.65)
					(thickness 0.15)
				)
				(justify left bottom)
			)
		)
		(property "Value" "TP_0.75mm_SMD"
			(at 0 1.2 0)
			(layer "F.Fab")
			(hide yes)
			(effects
				(font
					(size 0.7 0.7)
					(thickness 0.15)
				)
				(justify left bottom)
			)
		)
		(property "Description" "SMT test point"
			(at 0 0 0)
			(layer "F.Fab")
			(hide yes)
			(effects
				(font
					(size 1.27 1.27)
					(thickness 0.15)
				)
			)
		)
		(property "Author" "Antmicro"
			(at 0 0 0)
			(layer "F.Fab")
			(hide yes)
			(effects
				(font
					(size 1 1)
					(thickness 0.15)
				)
			)
		)
		(property "License" "Apache-2.0"
			(at 0 0 0)
			(layer "F.Fab")
			(hide yes)
			(effects
				(font
					(size 1 1)
					(thickness 0.15)
				)
			)
		)
		(property "MPN" ""
			(at 0 0 0)
			(layer "F.Fab")
			(hide yes)
			(effects
				(font
					(size 1 1)
					(thickness 0.15)
				)
			)
		)
		(property "Manufacturer" ""
			(at 0 0 0)
			(layer "F.Fab")
			(hide yes)
			(effects
				(font
					(size 1 1)
					(thickness 0.15)
				)
			)
		)
		(sheetname "/Power Supply/")
		(sheetfile "supply.kicad_sch")
		(attr exclude_from_pos_files)
		(fp_circle
			(center 0 0)
			(end 0.475 0)
			(stroke
				(width 0.05)
				(type default)
			)
			(fill no)
			(layer "F.CrtYd")
		)
		(fp_text user "${REFERENCE}"
			(at -0.4 2.7 0)
			(layer "F.Fab")
			(effects
				(font
					(size 0.7 0.7)
					(thickness 0.15)
				)
				(justify left bottom)
			)
		)
		(fp_text user "Author: Antmicro"
			(at -0.4 3.901 0)
			(layer "F.Fab")
			(effects
				(font
					(size 0.7 0.7)
					(thickness 0.15)
				)
				(justify left bottom)
			)
		)
		(fp_text user "License: Apache-2.0"
			(at -0.4 5.101 0)
			(layer "F.Fab")
			(effects
				(font
					(size 0.7 0.7)
					(thickness 0.15)
				)
				(justify left bottom)
			)
		)
		(pad "1" smd circle
			(at 0 0)
			(size 0.75 0.75)
			(layers "F.Cu" "F.Mask")
			(net 1 "GND")
			(pinfunction "1")
			(pintype "passive")
		)
	)
	(footprint "antmicro-footprints:R_0402_1005Metric"
		(layer "F.Cu")
		(at 122.03 113.15)
		(descr "Resistor SMD 0402")
		(tags "resistor SMD 0402")
		(property "Reference" "R81"
			(at -3.9 0.29 0)
			(layer "F.SilkS")
			(effects
				(font
					(size 0.65 0.65)
					(thickness 0.15)
				)
				(justify left bottom)
			)
		)
		(property "Value" "R_10k_0402"
			(at 0 1.4 0)
			(layer "F.Fab")
			(hide yes)
			(effects
				(font
					(size 0.7 0.7)
					(thickness 0.15)
				)
				(justify left bottom)
			)
		)
		(property "Datasheet" "https://www.bourns.com/docs/product-datasheets/cr.pdf"
			(at 0 0 0)
			(layer "F.Fab")
			(hide yes)
			(effects
				(font
					(size 1.27 1.27)
					(thickness 0.15)
				)
			)
		)
		(property "Description" "SMD Chip Resistor, 10 kohm, ± 1%, 62.5 mW, 0402 [1005 Metric], Thick Film, General Purpose"
			(at 0 0 0)
			(layer "F.Fab")
			(hide yes)
			(effects
				(font
					(size 1.27 1.27)
					(thickness 0.15)
				)
			)
		)
		(property "Author" "Antmicro"
			(at 0 0 0)
			(layer "F.Fab")
			(hide yes)
			(effects
				(font
					(size 1 1)
					(thickness 0.15)
				)
			)
		)
		(property "License" "Apache-2.0"
			(at 0 0 0)
			(layer "F.Fab")
			(hide yes)
			(effects
				(font
					(size 1 1)
					(thickness 0.15)
				)
			)
		)
		(property "MPN" "CR0402-FX-1002GLF"
			(at 0 0 0)
			(layer "F.Fab")
			(hide yes)
			(effects
				(font
					(size 1 1)
					(thickness 0.15)
				)
			)
		)
		(property "Manufacturer" "Bourns"
			(at 0 0 0)
			(layer "F.Fab")
			(hide yes)
			(effects
				(font
					(size 1 1)
					(thickness 0.15)
				)
			)
		)
		(property "Tolerance" "1%"
			(at 0 0 0)
			(layer "F.Fab")
			(hide yes)
			(effects
				(font
					(size 1 1)
					(thickness 0.15)
				)
			)
		)
		(property "Val" "10k"
			(at 0 0 0)
			(layer "F.Fab")
			(hide yes)
			(effects
				(font
					(size 1 1)
					(thickness 0.15)
				)
			)
		)
		(sheetname "/FPGA/")
		(sheetfile "fpga.kicad_sch")
		(attr smd)
		(fp_rect
			(start -0.925 -0.47)
			(end 0.925 0.47)
			(stroke
				(width 0.05)
				(type default)
			)
			(fill no)
			(layer "F.CrtYd")
		)
		(fp_rect
			(start -0.5 -0.25)
			(end 0.5 0.25)
			(stroke
				(width 0.15)
				(type solid)
			)
			(fill no)
			(layer "F.Fab")
		)
		(fp_text user "${REFERENCE}"
			(at -0.95 3.168 0)
			(layer "F.Fab")
			(effects
				(font
					(size 0.7 0.7)
					(thickness 0.15)
				)
				(justify left bottom)
			)
		)
		(fp_text user "License: Apache-2.0"
			(at -0.95 5.169 0)
			(layer "F.Fab")
			(effects
				(font
					(size 0.7 0.7)
					(thickness 0.15)
				)
				(justify left bottom)
			)
		)
		(fp_text user "Author: Antmicro"
			(at -0.95 4.169 0)
			(layer "F.Fab")
			(effects
				(font
					(size 0.7 0.7)
					(thickness 0.15)
				)
				(justify left bottom)
			)
		)
		(pad "1" smd roundrect
			(at -0.48 0)
			(size 0.59 0.64)
			(layers "F.Cu" "F.Mask" "F.Paste")
			(roundrect_rratio 0.25)
			(net 40 "/FPGA/DONE")
			(pintype "passive")
		)
		(pad "2" smd roundrect
			(at 0.48 0)
			(size 0.59 0.64)
			(layers "F.Cu" "F.Mask" "F.Paste")
			(roundrect_rratio 0.25)
			(net 2 "+3V3")
			(pintype "passive")
		)
	)
	(footprint "antmicro-footprints:R_0402_1005Metric"
		(layer "F.Cu")
		(at 127.75 116.75 -90)
		(descr "Resistor SMD 0402")
		(tags "resistor SMD 0402")
		(property "Reference" "R128"
			(at -0.81 -0.28 270)
			(layer "F.SilkS")
			(effects
				(font
					(size 0.65 0.65)
					(thickness 0.15)
				)
				(justify left bottom)
			)
		)
		(property "Value" "R_0R_0402"
			(at 0 1.4 270)
			(layer "F.Fab")
			(hide yes)
			(effects
				(font
					(size 0.7 0.7)
					(thickness 0.15)
				)
				(justify left bottom)
			)
		)
		(property "Datasheet" "https://industrial.panasonic.com/cdbs/www-data/pdf/RDA0000/AOA0000C301.pdf"
			(at 0 0 270)
			(layer "F.Fab")
			(hide yes)
			(effects
				(font
					(size 1.27 1.27)
					(thickness 0.15)
				)
			)
		)
		(property "Description" "SMD Chip Resistor, Jumper, 0 ohm, 100 mW, 0402 [1005 Metric], Thick Film, General Purpose"
			(at 0 0 270)
			(layer "F.Fab")
			(hide yes)
			(effects
				(font
					(size 1.27 1.27)
					(thickness 0.15)
				)
			)
		)
		(property "Author" "Antmicro"
			(at 11 244.5 0)
			(layer "F.Fab")
			(hide yes)
			(effects
				(font
					(size 1 1)
					(thickness 0.15)
				)
			)
		)
		(property "Current" "1A"
			(at 11 244.5 0)
			(layer "F.Fab")
			(hide yes)
			(effects
				(font
					(size 1 1)
					(thickness 0.15)
				)
			)
		)
		(property "License" "Apache-2.0"
			(at 11 244.5 0)
			(layer "F.Fab")
			(hide yes)
			(effects
				(font
					(size 1 1)
					(thickness 0.15)
				)
			)
		)
		(property "MPN" "ERJ2GE0R00X"
			(at 11 244.5 0)
			(layer "F.Fab")
			(hide yes)
			(effects
				(font
					(size 1 1)
					(thickness 0.15)
				)
			)
		)
		(property "Manufacturer" "Panasonic"
			(at 11 244.5 0)
			(layer "F.Fab")
			(hide yes)
			(effects
				(font
					(size 1 1)
					(thickness 0.15)
				)
			)
		)
		(property "Tolerance" "~"
			(at 11 244.5 0)
			(layer "F.Fab")
			(hide yes)
			(effects
				(font
					(size 1 1)
					(thickness 0.15)
				)
			)
		)
		(property "Val" "0R"
			(at 11 244.5 0)
			(layer "F.Fab")
			(hide yes)
			(effects
				(font
					(size 1 1)
					(thickness 0.15)
				)
			)
		)
		(sheetname "/Peripherals/")
		(sheetfile "peripherals.kicad_sch")
		(attr smd)
		(fp_rect
			(start -0.925 -0.47)
			(end 0.925 0.47)
			(stroke
				(width 0.05)
				(type default)
			)
			(fill no)
			(layer "F.CrtYd")
		)
		(fp_rect
			(start -0.5 -0.25)
			(end 0.5 0.25)
			(stroke
				(width 0.15)
				(type solid)
			)
			(fill no)
			(layer "F.Fab")
		)
		(fp_text user "${REFERENCE}"
			(at -0.95 3.168 270)
			(layer "F.Fab")
			(effects
				(font
					(size 0.7 0.7)
					(thickness 0.15)
				)
				(justify left bottom)
			)
		)
		(fp_text user "Author: Antmicro"
			(at -0.95 4.169 270)
			(layer "F.Fab")
			(effects
				(font
					(size 0.7 0.7)
					(thickness 0.15)
				)
				(justify left bottom)
			)
		)
		(fp_text user "License: Apache-2.0"
			(at -0.95 5.169 270)
			(layer "F.Fab")
			(effects
				(font
					(size 0.7 0.7)
					(thickness 0.15)
				)
				(justify left bottom)
			)
		)
		(pad "1" smd roundrect
			(at -0.48 0 270)
			(size 0.59 0.64)
			(layers "F.Cu" "F.Mask" "F.Paste")
			(roundrect_rratio 0.25)
			(net 108 "/Peripherals/FFC2_VSYNC0")
			(pintype "passive")
		)
		(pad "2" smd roundrect
			(at 0.48 0 270)
			(size 0.59 0.64)
			(layers "F.Cu" "F.Mask" "F.Paste")
			(roundrect_rratio 0.25)
			(net 343 "Net-(J6-Pad32)")
			(pintype "passive")
		)
	)
	(footprint "antmicro-footprints:C_0402_1005Metric"
		(layer "F.Cu")
		(at 89.1 78.9 90)
		(descr "Capacitor SMD 0402")
		(tags "capacitor SMD 0402")
		(property "Reference" "C59"
			(at 5.36 -1.17 90)
			(layer "F.SilkS")
			(effects
				(font
					(size 0.65 0.65)
					(thickness 0.15)
				)
				(justify left bottom)
			)
		)
		(property "Value" "C_470n_0402"
			(at 0 1.4 90)
			(layer "F.Fab")
			(hide yes)
			(effects
				(font
					(size 0.7 0.7)
					(thickness 0.15)
				)
				(justify left bottom)
			)
		)
		(property "Datasheet" "https://product.tdk.com/en/search/capacitor/ceramic/mlcc/info?part_no=C1005X5R1E474M050BB"
			(at 0 0 90)
			(layer "F.Fab")
			(hide yes)
			(effects
				(font
					(size 1.27 1.27)
					(thickness 0.15)
				)
			)
		)
		(property "Description" "SMD Multilayer Ceramic Capacitor, 0.47 µF, 25 V, 0402 [1005 Metric], ± 20%, X5R, C"
			(at 0 0 90)
			(layer "F.Fab")
			(hide yes)
			(effects
				(font
					(size 1.27 1.27)
					(thickness 0.15)
				)
			)
		)
		(property "Author" "Antmicro"
			(at 168 -10.2 0)
			(layer "F.Fab")
			(hide yes)
			(effects
				(font
					(size 1 1)
					(thickness 0.15)
				)
			)
		)
		(property "Dielectric" ""
			(at 168 -10.2 0)
			(layer "F.Fab")
			(hide yes)
			(effects
				(font
					(size 1 1)
					(thickness 0.15)
				)
			)
		)
		(property "License" "Apache-2.0"
			(at 168 -10.2 0)
			(layer "F.Fab")
			(hide yes)
			(effects
				(font
					(size 1 1)
					(thickness 0.15)
				)
			)
		)
		(property "MPN" "C1005X5R1E474M050BB"
			(at 168 -10.2 0)
			(layer "F.Fab")
			(hide yes)
			(effects
				(font
					(size 1 1)
					(thickness 0.15)
				)
			)
		)
		(property "Manufacturer" "TDK"
			(at 168 -10.2 0)
			(layer "F.Fab")
			(hide yes)
			(effects
				(font
					(size 1 1)
					(thickness 0.15)
				)
			)
		)
		(property "Val" "470n"
			(at 168 -10.2 0)
			(layer "F.Fab")
			(hide yes)
			(effects
				(font
					(size 1 1)
					(thickness 0.15)
				)
			)
		)
		(property "Voltage" ""
			(at 168 -10.2 0)
			(layer "F.Fab")
			(hide yes)
			(effects
				(font
					(size 1 1)
					(thickness 0.15)
				)
			)
		)
		(sheetname "/SDI/")
		(sheetfile "sdi.kicad_sch")
		(attr smd)
		(fp_rect
			(start -0.925 -0.47)
			(end 0.925 0.47)
			(stroke
				(width 0.05)
				(type default)
			)
			(fill no)
			(layer "F.CrtYd")
		)
		(fp_line
			(start 0.504 -0.25)
			(end 0.504 0.248)
			(stroke
				(width 0.15)
				(type solid)
			)
			(layer "F.Fab")
		)
		(fp_line
			(start -0.494 -0.25)
			(end 0.504 -0.25)
			(stroke
				(width 0.15)
				(type solid)
			)
			(layer "F.Fab")
		)
		(fp_line
			(start 0.504 0.248)
			(end -0.494 0.248)
			(stroke
				(width 0.15)
				(type solid)
			)
			(layer "F.Fab")
		)
		(fp_line
			(start -0.494 0.248)
			(end -0.494 -0.25)
			(stroke
				(width 0.15)
				(type solid)
			)
			(layer "F.Fab")
		)
		(fp_text user "License: Apache-2.0"
			(at -0.939 5.799 90)
			(layer "F.Fab")
			(effects
				(font
					(size 0.7 0.7)
					(thickness 0.15)
				)
				(justify left bottom)
			)
		)
		(fp_text user "Author: Antmicro"
			(at -0.939 3.399 90)
			(layer "F.Fab")
			(effects
				(font
					(size 0.7 0.7)
					(thickness 0.15)
				)
				(justify left bottom)
			)
		)
		(fp_text user "${REFERENCE}"
			(at -0.939 4.599 90)
			(layer "F.Fab")
			(effects
				(font
					(size 0.7 0.7)
					(thickness 0.15)
				)
				(justify left bottom)
			)
		)
		(pad "1" smd roundrect
			(at -0.48 0 90)
			(size 0.59 0.64)
			(layers "F.Cu" "F.Mask" "F.Paste")
			(roundrect_rratio 0.25)
			(net 291 "/SDI/AGC_N")
			(pintype "passive")
		)
		(pad "2" smd roundrect
			(at 0.48 0 90)
			(size 0.59 0.64)
			(layers "F.Cu" "F.Mask" "F.Paste")
			(roundrect_rratio 0.25)
			(net 292 "/SDI/AGC_P")
			(pintype "passive")
		)
	)
)
